(kicad_pcb
	(version 20260206)
	(generator "pcbnew")
	(generator_version "10.0")
	(general
		(thickness 1.6)
		(legacy_teardrops no)
	)
	(paper "A4")
	(title_block
		(title "04192023_DAF0TMB3IC0_F0TG_MB_C_brd_V02_OCP.brd")
		(comment 1 "Grand Teton / footprints 4851-4858 of 8354")
	)
	(layers
		(0 "F.Cu" signal "TOP")
		(4 "In1.Cu" signal "GND")
		(6 "In2.Cu" signal "IN1")
		(8 "In3.Cu" signal "GND1")
		(10 "In4.Cu" signal "IN2")
		(12 "In5.Cu" signal "GND2")
		(14 "In6.Cu" signal "IN3")
		(16 "In7.Cu" signal "GND3")
		(18 "In8.Cu" signal "VCC")
		(20 "In9.Cu" signal "VCC1")
		(22 "In10.Cu" signal "GND4")
		(24 "In11.Cu" signal "IN4")
		(26 "In12.Cu" signal "GND5")
		(28 "In13.Cu" signal "IN5")
		(30 "In14.Cu" signal "GND6")
		(32 "In15.Cu" signal "IN6")
		(34 "In16.Cu" signal "GND7")
		(2 "B.Cu" signal "BOTTOM")
		(9 "F.Adhes" user "F.Adhesive")
		(11 "B.Adhes" user "B.Adhesive")
		(13 "F.Paste" user "Package Geometry/Pastemask Top")
		(15 "B.Paste" user "Package Geometry/Pastemask Bottom")
		(5 "F.SilkS" user "Ref Des/Silkscreen Top")
		(7 "B.SilkS" user "Ref Des/Silkscreen Bottom")
		(1 "F.Mask" user "Board Geometry/Soldermask Top")
		(3 "B.Mask" user "Board Geometry/Soldermask Bottom")
		(17 "Dwgs.User" user "User.Drawings")
		(19 "Cmts.User" user "User.Comments")
		(21 "Eco1.User" user "User.Eco1")
		(23 "Eco2.User" user "User.Eco2")
		(25 "Edge.Cuts" user "Board Geometry/Outline")
		(27 "Margin" user)
		(31 "F.CrtYd" user "Package Geometry/Place Bound Top")
		(29 "B.CrtYd" user "Package Geometry/Place Bound Bottom")
		(35 "F.Fab" user "Ref Des/Assembly Top")
		(33 "B.Fab" user "Ref Des/Assembly Bottom")
	)
	(footprint ""
		(layer "F.Cu")
		(at 325.314056 -23.826216 -90)
		(property "Reference" "R5054"
			(at 0 0 270)
			(layer "F.SilkS")
			(hide yes)
			(effects
				(font
					(size 1.27 1.27)
				)
			)
		)
		(property "Value" ""
			(at 0 0 270)
			(layer "F.Fab")
			(effects
				(font
					(size 1.27 1.27)
				)
			)
		)
		(duplicate_pad_numbers_are_jumpers no)
		(fp_line
			(start -0.7874 0.4064)
			(end -0.7874 -0.4064)
			(stroke
				(width 0.1524)
				(type default)
			)
			(layer "F.SilkS")
		)
		(fp_line
			(start 0.7874 0.4064)
			(end -0.7874 0.4064)
			(stroke
				(width 0.1524)
				(type default)
			)
			(layer "F.SilkS")
		)
		(fp_line
			(start -0.7874 -0.4064)
			(end 0.7874 -0.4064)
			(stroke
				(width 0.1524)
				(type default)
			)
			(layer "F.SilkS")
		)
		(fp_line
			(start 0.7874 -0.4064)
			(end 0.7874 0.4064)
			(stroke
				(width 0.1524)
				(type default)
			)
			(layer "F.SilkS")
		)
		(fp_line
			(start -0.67945 0.3048)
			(end -0.67945 -0.305054)
			(stroke
				(width 0.1)
				(type default)
			)
			(layer "F.Fab")
		)
		(fp_line
			(start -0.12065 0.3048)
			(end -0.67945 0.3048)
			(stroke
				(width 0.1)
				(type default)
			)
			(layer "F.Fab")
		)
		(fp_line
			(start 0.120396 0.3048)
			(end 0.120396 0.2794)
			(stroke
				(width 0.1)
				(type default)
			)
			(layer "F.Fab")
		)
		(fp_line
			(start 0.67945 0.3048)
			(end 0.120396 0.3048)
			(stroke
				(width 0.1)
				(type default)
			)
			(layer "F.Fab")
		)
		(fp_line
			(start -0.12065 0.2794)
			(end -0.12065 0.3048)
			(stroke
				(width 0.1)
				(type default)
			)
			(layer "F.Fab")
		)
		(fp_line
			(start 0.120396 0.2794)
			(end -0.12065 0.2794)
			(stroke
				(width 0.1)
				(type default)
			)
			(layer "F.Fab")
		)
		(fp_line
			(start -0.12065 -0.2794)
			(end 0.12065 -0.2794)
			(stroke
				(width 0.1)
				(type default)
			)
			(layer "F.Fab")
		)
		(fp_line
			(start 0.12065 -0.2794)
			(end 0.12065 -0.3048)
			(stroke
				(width 0.1)
				(type default)
			)
			(layer "F.Fab")
		)
		(fp_line
			(start 0.12065 -0.3048)
			(end 0.67945 -0.3048)
			(stroke
				(width 0.1)
				(type default)
			)
			(layer "F.Fab")
		)
		(fp_line
			(start 0.67945 -0.3048)
			(end 0.67945 0.3048)
			(stroke
				(width 0.1)
				(type default)
			)
			(layer "F.Fab")
		)
		(fp_line
			(start -0.67945 -0.305054)
			(end -0.12065 -0.305054)
			(stroke
				(width 0.1)
				(type default)
			)
			(layer "F.Fab")
		)
		(fp_line
			(start -0.12065 -0.305054)
			(end -0.12065 -0.2794)
			(stroke
				(width 0.1)
				(type default)
			)
			(layer "F.Fab")
		)
		(pad "1" smd circle
			(at -0.40005 0 270)
			(size 0 0)
			(layers "F.Cu" "F.Mask" "F.Paste")
			(net "P3V3_RTC_AUX_R")
		)
		(pad "2" smd circle
			(at 0.40005 0 270)
			(size 0 0)
			(layers "F.Cu" "F.Mask" "F.Paste")
			(net "P1V5_BAT_OUT_R")
		)
	)
	(footprint ""
		(layer "F.Cu")
		(at 172.540422 -417.551616)
		(property "Reference" "R9006"
			(at 0 0 0)
			(layer "F.SilkS")
			(hide yes)
			(effects
				(font
					(size 1.27 1.27)
				)
			)
		)
		(property "Value" ""
			(at 0 0 0)
			(layer "F.Fab")
			(effects
				(font
					(size 1.27 1.27)
				)
			)
		)
		(duplicate_pad_numbers_are_jumpers no)
		(fp_line
			(start -0.7874 -0.4064)
			(end 0.7874 -0.4064)
			(stroke
				(width 0.1524)
				(type default)
			)
			(layer "F.SilkS")
		)
		(fp_line
			(start -0.7874 0.4064)
			(end -0.7874 -0.4064)
			(stroke
				(width 0.1524)
				(type default)
			)
			(layer "F.SilkS")
		)
		(fp_line
			(start 0.7874 -0.4064)
			(end 0.7874 0.4064)
			(stroke
				(width 0.1524)
				(type default)
			)
			(layer "F.SilkS")
		)
		(fp_line
			(start 0.7874 0.4064)
			(end -0.7874 0.4064)
			(stroke
				(width 0.1524)
				(type default)
			)
			(layer "F.SilkS")
		)
		(fp_line
			(start -0.67945 -0.305054)
			(end -0.12065 -0.305054)
			(stroke
				(width 0.1)
				(type default)
			)
			(layer "F.Fab")
		)
		(fp_line
			(start -0.67945 0.3048)
			(end -0.67945 -0.305054)
			(stroke
				(width 0.1)
				(type default)
			)
			(layer "F.Fab")
		)
		(fp_line
			(start -0.12065 -0.305054)
			(end -0.12065 -0.2794)
			(stroke
				(width 0.1)
				(type default)
			)
			(layer "F.Fab")
		)
		(fp_line
			(start -0.12065 -0.2794)
			(end 0.12065 -0.2794)
			(stroke
				(width 0.1)
				(type default)
			)
			(layer "F.Fab")
		)
		(fp_line
			(start -0.12065 0.2794)
			(end -0.12065 0.3048)
			(stroke
				(width 0.1)
				(type default)
			)
			(layer "F.Fab")
		)
		(fp_line
			(start -0.12065 0.3048)
			(end -0.67945 0.3048)
			(stroke
				(width 0.1)
				(type default)
			)
			(layer "F.Fab")
		)
		(fp_line
			(start 0.120396 0.2794)
			(end -0.12065 0.2794)
			(stroke
				(width 0.1)
				(type default)
			)
			(layer "F.Fab")
		)
		(fp_line
			(start 0.120396 0.3048)
			(end 0.120396 0.2794)
			(stroke
				(width 0.1)
				(type default)
			)
			(layer "F.Fab")
		)
		(fp_line
			(start 0.12065 -0.3048)
			(end 0.67945 -0.3048)
			(stroke
				(width 0.1)
				(type default)
			)
			(layer "F.Fab")
		)
		(fp_line
			(start 0.12065 -0.2794)
			(end 0.12065 -0.3048)
			(stroke
				(width 0.1)
				(type default)
			)
			(layer "F.Fab")
		)
		(fp_line
			(start 0.67945 -0.3048)
			(end 0.67945 0.3048)
			(stroke
				(width 0.1)
				(type default)
			)
			(layer "F.Fab")
		)
		(fp_line
			(start 0.67945 0.3048)
			(end 0.120396 0.3048)
			(stroke
				(width 0.1)
				(type default)
			)
			(layer "F.Fab")
		)
		(pad "1" smd circle
			(at -0.40005 0)
			(size 0 0)
			(layers "F.Cu" "F.Mask" "F.Paste")
			(net "P3V3_AUX")
		)
		(pad "2" smd circle
			(at 0.40005 0)
			(size 0 0)
			(layers "F.Cu" "F.Mask" "F.Paste")
			(net "PRSNT_CABLE_SWB_B2_N")
		)
	)
	(footprint ""
		(layer "F.Cu")
		(at 149.990048 -26.68778 -90)
		(property "Reference" "R6024"
			(at 0 0 270)
			(layer "F.SilkS")
			(hide yes)
			(effects
				(font
					(size 1.27 1.27)
				)
			)
		)
		(property "Value" ""
			(at 0 0 270)
			(layer "F.Fab")
			(effects
				(font
					(size 1.27 1.27)
				)
			)
		)
		(duplicate_pad_numbers_are_jumpers no)
		(fp_line
			(start -0.7874 0.4064)
			(end -0.7874 -0.4064)
			(stroke
				(width 0.1524)
				(type default)
			)
			(layer "F.SilkS")
		)
		(fp_line
			(start 0.7874 0.4064)
			(end -0.7874 0.4064)
			(stroke
				(width 0.1524)
				(type default)
			)
			(layer "F.SilkS")
		)
		(fp_line
			(start -0.7874 -0.4064)
			(end 0.7874 -0.4064)
			(stroke
				(width 0.1524)
				(type default)
			)
			(layer "F.SilkS")
		)
		(fp_line
			(start 0.7874 -0.4064)
			(end 0.7874 0.4064)
			(stroke
				(width 0.1524)
				(type default)
			)
			(layer "F.SilkS")
		)
		(fp_line
			(start -0.67945 0.3048)
			(end -0.67945 -0.305054)
			(stroke
				(width 0.1)
				(type default)
			)
			(layer "F.Fab")
		)
		(fp_line
			(start -0.12065 0.3048)
			(end -0.67945 0.3048)
			(stroke
				(width 0.1)
				(type default)
			)
			(layer "F.Fab")
		)
		(fp_line
			(start 0.120396 0.3048)
			(end 0.120396 0.2794)
			(stroke
				(width 0.1)
				(type default)
			)
			(layer "F.Fab")
		)
		(fp_line
			(start 0.67945 0.3048)
			(end 0.120396 0.3048)
			(stroke
				(width 0.1)
				(type default)
			)
			(layer "F.Fab")
		)
		(fp_line
			(start -0.12065 0.2794)
			(end -0.12065 0.3048)
			(stroke
				(width 0.1)
				(type default)
			)
			(layer "F.Fab")
		)
		(fp_line
			(start 0.120396 0.2794)
			(end -0.12065 0.2794)
			(stroke
				(width 0.1)
				(type default)
			)
			(layer "F.Fab")
		)
		(fp_line
			(start -0.12065 -0.2794)
			(end 0.12065 -0.2794)
			(stroke
				(width 0.1)
				(type default)
			)
			(layer "F.Fab")
		)
		(fp_line
			(start 0.12065 -0.2794)
			(end 0.12065 -0.3048)
			(stroke
				(width 0.1)
				(type default)
			)
			(layer "F.Fab")
		)
		(fp_line
			(start 0.12065 -0.3048)
			(end 0.67945 -0.3048)
			(stroke
				(width 0.1)
				(type default)
			)
			(layer "F.Fab")
		)
		(fp_line
			(start 0.67945 -0.3048)
			(end 0.67945 0.3048)
			(stroke
				(width 0.1)
				(type default)
			)
			(layer "F.Fab")
		)
		(fp_line
			(start -0.67945 -0.305054)
			(end -0.12065 -0.305054)
			(stroke
				(width 0.1)
				(type default)
			)
			(layer "F.Fab")
		)
		(fp_line
			(start -0.12065 -0.305054)
			(end -0.12065 -0.2794)
			(stroke
				(width 0.1)
				(type default)
			)
			(layer "F.Fab")
		)
		(pad "1" smd circle
			(at -0.40005 0 270)
			(size 0 0)
			(layers "F.Cu" "F.Mask" "F.Paste")
			(net "P3V3_AUX")
		)
		(pad "2" smd circle
			(at 0.40005 0 270)
			(size 0 0)
			(layers "F.Cu" "F.Mask" "F.Paste")
			(net "SGPIO_SCM_INTR_N")
		)
	)
	(footprint ""
		(layer "F.Cu")
		(at 330.96962 -397.726154 180)
		(property "Reference" "R1369"
			(at 0 0 180)
			(layer "F.SilkS")
			(hide yes)
			(effects
				(font
					(size 1.27 1.27)
				)
			)
		)
		(property "Value" ""
			(at 0 0 180)
			(layer "F.Fab")
			(effects
				(font
					(size 1.27 1.27)
				)
			)
		)
		(duplicate_pad_numbers_are_jumpers no)
		(fp_line
			(start 0.32512 0.175006)
			(end -0.32512 0.175006)
			(stroke
				(width 0.1)
				(type default)
			)
			(layer "F.Fab")
		)
		(fp_line
			(start 0.32512 -0.175006)
			(end 0.32512 0.175006)
			(stroke
				(width 0.1)
				(type default)
			)
			(layer "F.Fab")
		)
		(fp_line
			(start -0.32512 0.175006)
			(end -0.32512 -0.175006)
			(stroke
				(width 0.1)
				(type default)
			)
			(layer "F.Fab")
		)
		(fp_line
			(start -0.32512 -0.175006)
			(end 0.32512 -0.175006)
			(stroke
				(width 0.1)
				(type default)
			)
			(layer "F.Fab")
		)
		(pad "1" smd rect
			(at -0.2667 0 180)
			(size 0.3048 0.381)
			(layers "F.Cu" "F.Mask" "F.Paste")
			(net "P1V8_CPU0_RT_1D")
		)
		(pad "2" smd rect
			(at 0.2667 0)
			(size 0.3048 0.381)
			(layers "F.Cu" "F.Mask" "F.Paste")
			(net "RXDET_BYP_RT_CPU0_P0")
		)
	)
	(footprint ""
		(layer "F.Cu")
		(at 302.133 -354.711 180)
		(property "Reference" "PR40"
			(at 0 0 180)
			(layer "F.SilkS")
			(hide yes)
			(effects
				(font
					(size 1.27 1.27)
				)
			)
		)
		(property "Value" ""
			(at 0 0 180)
			(layer "F.Fab")
			(effects
				(font
					(size 1.27 1.27)
				)
			)
		)
		(duplicate_pad_numbers_are_jumpers no)
		(fp_line
			(start 0.7874 0.4064)
			(end -0.7874 0.4064)
			(stroke
				(width 0.1524)
				(type default)
			)
			(layer "F.SilkS")
		)
		(fp_line
			(start 0.7874 -0.4064)
			(end 0.7874 0.4064)
			(stroke
				(width 0.1524)
				(type default)
			)
			(layer "F.SilkS")
		)
		(fp_line
			(start -0.7874 0.4064)
			(end -0.7874 -0.4064)
			(stroke
				(width 0.1524)
				(type default)
			)
			(layer "F.SilkS")
		)
		(fp_line
			(start -0.7874 -0.4064)
			(end 0.7874 -0.4064)
			(stroke
				(width 0.1524)
				(type default)
			)
			(layer "F.SilkS")
		)
		(fp_line
			(start 0.67945 0.3048)
			(end 0.120396 0.3048)
			(stroke
				(width 0.1)
				(type default)
			)
			(layer "F.Fab")
		)
		(fp_line
			(start 0.67945 -0.3048)
			(end 0.67945 0.3048)
			(stroke
				(width 0.1)
				(type default)
			)
			(layer "F.Fab")
		)
		(fp_line
			(start 0.12065 -0.2794)
			(end 0.12065 -0.3048)
			(stroke
				(width 0.1)
				(type default)
			)
			(layer "F.Fab")
		)
		(fp_line
			(start 0.12065 -0.3048)
			(end 0.67945 -0.3048)
			(stroke
				(width 0.1)
				(type default)
			)
			(layer "F.Fab")
		)
		(fp_line
			(start 0.120396 0.3048)
			(end 0.120396 0.2794)
			(stroke
				(width 0.1)
				(type default)
			)
			(layer "F.Fab")
		)
		(fp_line
			(start 0.120396 0.2794)
			(end -0.12065 0.2794)
			(stroke
				(width 0.1)
				(type default)
			)
			(layer "F.Fab")
		)
		(fp_line
			(start -0.12065 0.3048)
			(end -0.67945 0.3048)
			(stroke
				(width 0.1)
				(type default)
			)
			(layer "F.Fab")
		)
		(fp_line
			(start -0.12065 0.2794)
			(end -0.12065 0.3048)
			(stroke
				(width 0.1)
				(type default)
			)
			(layer "F.Fab")
		)
		(fp_line
			(start -0.12065 -0.2794)
			(end 0.12065 -0.2794)
			(stroke
				(width 0.1)
				(type default)
			)
			(layer "F.Fab")
		)
		(fp_line
			(start -0.12065 -0.305054)
			(end -0.12065 -0.2794)
			(stroke
				(width 0.1)
				(type default)
			)
			(layer "F.Fab")
		)
		(fp_line
			(start -0.67945 0.3048)
			(end -0.67945 -0.305054)
			(stroke
				(width 0.1)
				(type default)
			)
			(layer "F.Fab")
		)
		(fp_line
			(start -0.67945 -0.305054)
			(end -0.12065 -0.305054)
			(stroke
				(width 0.1)
				(type default)
			)
			(layer "F.Fab")
		)
		(pad "1" smd circle
			(at -0.40005 0 180)
			(size 0 0)
			(layers "F.Cu" "F.Mask" "F.Paste")
			(net "SVID_PVDDCR_CPU1_P0_SVTI")
		)
		(pad "2" smd circle
			(at 0.40005 0 180)
			(size 0 0)
			(layers "F.Cu" "F.Mask" "F.Paste")
			(net "GND")
		)
	)
	(footprint ""
		(layer "F.Cu")
		(at 131.099306 -408.517344 -90)
		(property "Reference" "C6703"
			(at 0 0 270)
			(layer "F.SilkS")
			(hide yes)
			(effects
				(font
					(size 1.27 1.27)
				)
			)
		)
		(property "Value" ""
			(at 0 0 270)
			(layer "F.Fab")
			(effects
				(font
					(size 1.27 1.27)
				)
			)
		)
		(duplicate_pad_numbers_are_jumpers no)
		(fp_line
			(start -0.299974 0.150114)
			(end -0.299974 -0.150114)
			(stroke
				(width 0.1)
				(type default)
			)
			(layer "F.Fab")
		)
		(fp_line
			(start 0.299974 0.150114)
			(end -0.299974 0.150114)
			(stroke
				(width 0.1)
				(type default)
			)
			(layer "F.Fab")
		)
		(fp_line
			(start -0.299974 -0.150114)
			(end 0.299974 -0.150114)
			(stroke
				(width 0.1)
				(type default)
			)
			(layer "F.Fab")
		)
		(fp_line
			(start 0.299974 -0.150114)
			(end 0.299974 0.150114)
			(stroke
				(width 0.1)
				(type default)
			)
			(layer "F.Fab")
		)
		(pad "1" smd rect
			(at -0.2667 0 270)
			(size 0.3048 0.381)
			(layers "F.Cu" "F.Mask" "F.Paste")
			(net "P5E_CPU1_P2_TX_BUF_C_DP<5>")
		)
		(pad "2" smd rect
			(at 0.2667 0 270)
			(size 0.3048 0.381)
			(layers "F.Cu" "F.Mask" "F.Paste")
			(net "P5E_CPU1_P2_TX_BUF_DP<5>")
		)
	)
	(footprint ""
		(layer "F.Cu")
		(at 388.213092 -378.95403 -90)
		(property "Reference" "C877"
			(at 0 0 270)
			(layer "F.SilkS")
			(hide yes)
			(effects
				(font
					(size 1.27 1.27)
				)
			)
		)
		(property "Value" ""
			(at 0 0 270)
			(layer "F.Fab")
			(effects
				(font
					(size 1.27 1.27)
				)
			)
		)
		(duplicate_pad_numbers_are_jumpers no)
		(fp_line
			(start -0.299974 0.150114)
			(end -0.299974 -0.150114)
			(stroke
				(width 0.1)
				(type default)
			)
			(layer "F.Fab")
		)
		(fp_line
			(start 0.299974 0.150114)
			(end -0.299974 0.150114)
			(stroke
				(width 0.1)
				(type default)
			)
			(layer "F.Fab")
		)
		(fp_line
			(start -0.299974 -0.150114)
			(end 0.299974 -0.150114)
			(stroke
				(width 0.1)
				(type default)
			)
			(layer "F.Fab")
		)
		(fp_line
			(start 0.299974 -0.150114)
			(end 0.299974 0.150114)
			(stroke
				(width 0.1)
				(type default)
			)
			(layer "F.Fab")
		)
		(pad "1" smd rect
			(at -0.2667 0 270)
			(size 0.3048 0.381)
			(layers "F.Cu" "F.Mask" "F.Paste")
			(net "P5E_CPU0_P3_TX_C_DP<12>")
		)
		(pad "2" smd rect
			(at 0.2667 0 270)
			(size 0.3048 0.381)
			(layers "F.Cu" "F.Mask" "F.Paste")
			(net "P5E_CPU0_P3_TX_DP<12>")
		)
	)
	(footprint ""
		(layer "F.Cu")
		(at 66.369438 -31.887922 90)
		(property "Reference" "PC2166"
			(at 0 0 90)
			(layer "F.SilkS")
			(hide yes)
			(effects
				(font
					(size 1.27 1.27)
				)
			)
		)
		(property "Value" ""
			(at 0 0 90)
			(layer "F.Fab")
			(effects
				(font
					(size 1.27 1.27)
				)
			)
		)
		(duplicate_pad_numbers_are_jumpers no)
		(fp_line
			(start 0.7874 -0.4064)
			(end 0.7874 0.4064)
			(stroke
				(width 0.1524)
				(type default)
			)
			(layer "F.SilkS")
		)
		(fp_line
			(start -0.7874 -0.4064)
			(end 0.7874 -0.4064)
			(stroke
				(width 0.1524)
				(type default)
			)
			(layer "F.SilkS")
		)
		(fp_line
			(start 0.7874 0.4064)
			(end -0.7874 0.4064)
			(stroke
				(width 0.1524)
				(type default)
			)
			(layer "F.SilkS")
		)
		(fp_line
			(start -0.7874 0.4064)
			(end -0.7874 -0.4064)
			(stroke
				(width 0.1524)
				(type default)
			)
			(layer "F.SilkS")
		)
		(fp_line
			(start -0.12065 -0.305054)
			(end -0.12065 -0.2794)
			(stroke
				(width 0.1)
				(type default)
			)
			(layer "F.Fab")
		)
		(fp_line
			(start -0.67945 -0.305054)
			(end -0.12065 -0.305054)
			(stroke
				(width 0.1)
				(type default)
			)
			(layer "F.Fab")
		)
		(fp_line
			(start 0.67945 -0.3048)
			(end 0.67945 0.3048)
			(stroke
				(width 0.1)
				(type default)
			)
			(layer "F.Fab")
		)
		(fp_line
			(start 0.12065 -0.3048)
			(end 0.67945 -0.3048)
			(stroke
				(width 0.1)
				(type default)
			)
			(layer "F.Fab")
		)
		(fp_line
			(start 0.12065 -0.2794)
			(end 0.12065 -0.3048)
			(stroke
				(width 0.1)
				(type default)
			)
			(layer "F.Fab")
		)
		(fp_line
			(start -0.12065 -0.2794)
			(end 0.12065 -0.2794)
			(stroke
				(width 0.1)
				(type default)
			)
			(layer "F.Fab")
		)
		(fp_line
			(start 0.120396 0.2794)
			(end -0.12065 0.2794)
			(stroke
				(width 0.1)
				(type default)
			)
			(layer "F.Fab")
		)
		(fp_line
			(start -0.12065 0.2794)
			(end -0.12065 0.3048)
			(stroke
				(width 0.1)
				(type default)
			)
			(layer "F.Fab")
		)
		(fp_line
			(start 0.67945 0.3048)
			(end 0.120396 0.3048)
			(stroke
				(width 0.1)
				(type default)
			)
			(layer "F.Fab")
		)
		(fp_line
			(start 0.120396 0.3048)
			(end 0.120396 0.2794)
			(stroke
				(width 0.1)
				(type default)
			)
			(layer "F.Fab")
		)
		(fp_line
			(start -0.12065 0.3048)
			(end -0.67945 0.3048)
			(stroke
				(width 0.1)
				(type default)
			)
			(layer "F.Fab")
		)
		(fp_line
			(start -0.67945 0.3048)
			(end -0.67945 -0.305054)
			(stroke
				(width 0.1)
				(type default)
			)
			(layer "F.Fab")
		)
		(pad "1" smd circle
			(at -0.40005 0 90)
			(size 0 0)
			(layers "F.Cu" "F.Mask" "F.Paste")
			(net "P12V_OCP_SS_2")
		)
		(pad "2" smd circle
			(at 0.40005 0 90)
			(size 0 0)
			(layers "F.Cu" "F.Mask" "F.Paste")
			(net "GND")
		)
	)
)
